# T6G (Grand Teton) — schematic netlist excerpt (pin names and nets, part order shuffled) for the footprints in the layout excerpt that follows; sources: Cadence DE-HDL packaged netlist, KiCad conversion of 04192023_DAF0TMB3IC0_F0TG_MB_C_brd_V02_OCP.brd

PR3951  Q_RES  10K 1% CHIP  pkg 0402LF  page 147 : A = P12V_E1S_FLTB_0 ; B = P3V3_AUX
R715  Q_RES  10K 1% CHIP  pkg 0201LF  page 320 : A = GPIO3_RT_CPU1_P0 ; B = GND
PC79  Q_CAP  2.2UF 10V 10% X6S  pkg C0402  page 201 : A = PVDDCR_CPU1_P0_VCC1 ; B = GND

(kicad_pcb
	(version 20260206)
	(generator "pcbnew")
	(generator_version "10.0")
	(general
		(thickness 1.6)
		(legacy_teardrops no)
	)
	(paper "A4")
	(title_block
		(title "04192023_DAF0TMB3IC0_F0TG_MB_C_brd_V02_OCP.brd")
		(comment 1 "Grand Teton / footprints 1796-1798 of 8354")
	)
	(layers
		(0 "F.Cu" signal "TOP")
		(4 "In1.Cu" signal "GND")
		(6 "In2.Cu" signal "IN1")
		(8 "In3.Cu" signal "GND1")
		(10 "In4.Cu" signal "IN2")
		(12 "In5.Cu" signal "GND2")
		(14 "In6.Cu" signal "IN3")
		(16 "In7.Cu" signal "GND3")
		(18 "In8.Cu" signal "VCC")
		(20 "In9.Cu" signal "VCC1")
		(22 "In10.Cu" signal "GND4")
		(24 "In11.Cu" signal "IN4")
		(26 "In12.Cu" signal "GND5")
		(28 "In13.Cu" signal "IN5")
		(30 "In14.Cu" signal "GND6")
		(32 "In15.Cu" signal "IN6")
		(34 "In16.Cu" signal "GND7")
		(2 "B.Cu" signal "BOTTOM")
		(9 "F.Adhes" user "F.Adhesive")
		(11 "B.Adhes" user "B.Adhesive")
		(13 "F.Paste" user "Package Geometry/Pastemask Top")
		(15 "B.Paste" user "Package Geometry/Pastemask Bottom")
		(5 "F.SilkS" user "Ref Des/Silkscreen Top")
		(7 "B.SilkS" user "Ref Des/Silkscreen Bottom")
		(1 "F.Mask" user "Board Geometry/Soldermask Top")
		(3 "B.Mask" user "Board Geometry/Soldermask Bottom")
		(17 "Dwgs.User" user "User.Drawings")
		(19 "Cmts.User" user "User.Comments")
		(21 "Eco1.User" user "User.Eco1")
		(23 "Eco2.User" user "User.Eco2")
		(25 "Edge.Cuts" user "Board Geometry/Outline")
		(27 "Margin" user)
		(31 "F.CrtYd" user "Package Geometry/Place Bound Top")
		(29 "B.CrtYd" user "Package Geometry/Place Bound Bottom")
		(35 "F.Fab" user "Ref Des/Assembly Top")
		(33 "B.Fab" user "Ref Des/Assembly Bottom")
	)
	(footprint ""
		(layer "F.Cu")
		(at 255.37033 -55.860442 90)
		(property "Reference" "PR3951"
			(at 0 0 90)
			(layer "F.SilkS")
			(hide yes)
			(effects
				(font
					(size 1.27 1.27)
				)
			)
		)
		(property "Value" ""
			(at 0 0 90)
			(layer "F.Fab")
			(effects
				(font
					(size 1.27 1.27)
				)
			)
		)
		(duplicate_pad_numbers_are_jumpers no)
		(fp_line
			(start 0.7874 -0.4064)
			(end 0.7874 0.4064)
			(stroke
				(width 0.1524)
				(type default)
			)
			(layer "F.SilkS")
		)
		(fp_line
			(start -0.7874 -0.4064)
			(end 0.7874 -0.4064)
			(stroke
				(width 0.1524)
				(type default)
			)
			(layer "F.SilkS")
		)
		(fp_line
			(start 0.7874 0.4064)
			(end -0.7874 0.4064)
			(stroke
				(width 0.1524)
				(type default)
			)
			(layer "F.SilkS")
		)
		(fp_line
			(start -0.7874 0.4064)
			(end -0.7874 -0.4064)
			(stroke
				(width 0.1524)
				(type default)
			)
			(layer "F.SilkS")
		)
		(fp_line
			(start -0.12065 -0.305054)
			(end -0.12065 -0.2794)
			(stroke
				(width 0.1)
				(type default)
			)
			(layer "F.Fab")
		)
		(fp_line
			(start -0.67945 -0.305054)
			(end -0.12065 -0.305054)
			(stroke
				(width 0.1)
				(type default)
			)
			(layer "F.Fab")
		)
		(fp_line
			(start 0.67945 -0.3048)
			(end 0.67945 0.3048)
			(stroke
				(width 0.1)
				(type default)
			)
			(layer "F.Fab")
		)
		(fp_line
			(start 0.12065 -0.3048)
			(end 0.67945 -0.3048)
			(stroke
				(width 0.1)
				(type default)
			)
			(layer "F.Fab")
		)
		(fp_line
			(start 0.12065 -0.2794)
			(end 0.12065 -0.3048)
			(stroke
				(width 0.1)
				(type default)
			)
			(layer "F.Fab")
		)
		(fp_line
			(start -0.12065 -0.2794)
			(end 0.12065 -0.2794)
			(stroke
				(width 0.1)
				(type default)
			)
			(layer "F.Fab")
		)
		(fp_line
			(start 0.120396 0.2794)
			(end -0.12065 0.2794)
			(stroke
				(width 0.1)
				(type default)
			)
			(layer "F.Fab")
		)
		(fp_line
			(start -0.12065 0.2794)
			(end -0.12065 0.3048)
			(stroke
				(width 0.1)
				(type default)
			)
			(layer "F.Fab")
		)
		(fp_line
			(start 0.67945 0.3048)
			(end 0.120396 0.3048)
			(stroke
				(width 0.1)
				(type default)
			)
			(layer "F.Fab")
		)
		(fp_line
			(start 0.120396 0.3048)
			(end 0.120396 0.2794)
			(stroke
				(width 0.1)
				(type default)
			)
			(layer "F.Fab")
		)
		(fp_line
			(start -0.12065 0.3048)
			(end -0.67945 0.3048)
			(stroke
				(width 0.1)
				(type default)
			)
			(layer "F.Fab")
		)
		(fp_line
			(start -0.67945 0.3048)
			(end -0.67945 -0.305054)
			(stroke
				(width 0.1)
				(type default)
			)
			(layer "F.Fab")
		)
		(pad "1" smd circle
			(at -0.40005 0 90)
			(size 0 0)
			(layers "F.Cu" "F.Mask" "F.Paste")
			(net "P12V_E1S_FLTB_0")
		)
		(pad "2" smd circle
			(at 0.40005 0 90)
			(size 0 0)
			(layers "F.Cu" "F.Mask" "F.Paste")
			(net "P3V3_AUX")
		)
	)
	(footprint ""
		(layer "F.Cu")
		(at 331.37602 -337.638898 90)
		(property "Reference" "PC79"
			(at 0 0 90)
			(layer "F.SilkS")
			(hide yes)
			(effects
				(font
					(size 1.27 1.27)
				)
			)
		)
		(property "Value" ""
			(at 0 0 90)
			(layer "F.Fab")
			(effects
				(font
					(size 1.27 1.27)
				)
			)
		)
		(duplicate_pad_numbers_are_jumpers no)
		(fp_line
			(start 0.7874 -0.4064)
			(end 0.7874 0.4064)
			(stroke
				(width 0.1524)
				(type default)
			)
			(layer "F.SilkS")
		)
		(fp_line
			(start -0.7874 -0.4064)
			(end 0.7874 -0.4064)
			(stroke
				(width 0.1524)
				(type default)
			)
			(layer "F.SilkS")
		)
		(fp_line
			(start 0.7874 0.4064)
			(end 0.435102 0.4064)
			(stroke
				(width 0.1524)
				(type default)
			)
			(layer "F.SilkS")
		)
		(fp_line
			(start -0.225298 0.4064)
			(end -0.7874 0.4064)
			(stroke
				(width 0.1524)
				(type default)
			)
			(layer "F.SilkS")
		)
		(fp_line
			(start -0.7874 0.4064)
			(end -0.7874 -0.4064)
			(stroke
				(width 0.1524)
				(type default)
			)
			(layer "F.SilkS")
		)
		(fp_line
			(start -0.12065 -0.305054)
			(end -0.12065 -0.2794)
			(stroke
				(width 0.1)
				(type default)
			)
			(layer "F.Fab")
		)
		(fp_line
			(start -0.67945 -0.305054)
			(end -0.12065 -0.305054)
			(stroke
				(width 0.1)
				(type default)
			)
			(layer "F.Fab")
		)
		(fp_line
			(start 0.67945 -0.3048)
			(end 0.67945 0.3048)
			(stroke
				(width 0.1)
				(type default)
			)
			(layer "F.Fab")
		)
		(fp_line
			(start 0.12065 -0.3048)
			(end 0.67945 -0.3048)
			(stroke
				(width 0.1)
				(type default)
			)
			(layer "F.Fab")
		)
		(fp_line
			(start 0.12065 -0.2794)
			(end 0.12065 -0.3048)
			(stroke
				(width 0.1)
				(type default)
			)
			(layer "F.Fab")
		)
		(fp_line
			(start -0.12065 -0.2794)
			(end 0.12065 -0.2794)
			(stroke
				(width 0.1)
				(type default)
			)
			(layer "F.Fab")
		)
		(fp_line
			(start 0.120396 0.2794)
			(end -0.12065 0.2794)
			(stroke
				(width 0.1)
				(type default)
			)
			(layer "F.Fab")
		)
		(fp_line
			(start -0.12065 0.2794)
			(end -0.12065 0.3048)
			(stroke
				(width 0.1)
				(type default)
			)
			(layer "F.Fab")
		)
		(fp_line
			(start 0.67945 0.3048)
			(end 0.120396 0.3048)
			(stroke
				(width 0.1)
				(type default)
			)
			(layer "F.Fab")
		)
		(fp_line
			(start 0.120396 0.3048)
			(end 0.120396 0.2794)
			(stroke
				(width 0.1)
				(type default)
			)
			(layer "F.Fab")
		)
		(fp_line
			(start -0.12065 0.3048)
			(end -0.67945 0.3048)
			(stroke
				(width 0.1)
				(type default)
			)
			(layer "F.Fab")
		)
		(fp_line
			(start -0.67945 0.3048)
			(end -0.67945 -0.305054)
			(stroke
				(width 0.1)
				(type default)
			)
			(layer "F.Fab")
		)
		(pad "1" smd circle
			(at -0.40005 0 90)
			(size 0 0)
			(layers "F.Cu" "F.Mask" "F.Paste")
			(net "PVDDCR_CPU1_P0_VCC1")
		)
		(pad "2" smd circle
			(at 0.40005 0 90)
			(size 0 0)
			(layers "F.Cu" "F.Mask" "F.Paste")
			(net "GND")
		)
	)
	(footprint ""
		(layer "F.Cu")
		(at 43.265852 -384.66268)
		(property "Reference" "R715"
			(at 0 0 0)
			(layer "F.SilkS")
			(hide yes)
			(effects
				(font
					(size 1.27 1.27)
				)
			)
		)
		(property "Value" ""
			(at 0 0 0)
			(layer "F.Fab")
			(effects
				(font
					(size 1.27 1.27)
				)
			)
		)
		(duplicate_pad_numbers_are_jumpers no)
		(fp_line
			(start -0.32512 -0.175006)
			(end 0.32512 -0.175006)
			(stroke
				(width 0.1)
				(type default)
			)
			(layer "F.Fab")
		)
		(fp_line
			(start -0.32512 0.175006)
			(end -0.32512 -0.175006)
			(stroke
				(width 0.1)
				(type default)
			)
			(layer "F.Fab")
		)
		(fp_line
			(start 0.32512 -0.175006)
			(end 0.32512 0.175006)
			(stroke
				(width 0.1)
				(type default)
			)
			(layer "F.Fab")
		)
		(fp_line
			(start 0.32512 0.175006)
			(end -0.32512 0.175006)
			(stroke
				(width 0.1)
				(type default)
			)
			(layer "F.Fab")
		)
		(pad "1" smd rect
			(at -0.2667 0)
			(size 0.3048 0.381)
			(layers "F.Cu" "F.Mask" "F.Paste")
			(net "GPIO3_RT_CPU1_P0")
		)
		(pad "2" smd rect
			(at 0.2667 0 180)
			(size 0.3048 0.381)
			(layers "F.Cu" "F.Mask" "F.Paste")
			(net "GND")
		)
	)
)
